# T6G (Grand Teton) — schematic netlist excerpt (pin names and nets, part order shuffled) for the footprints in the layout excerpt that follows; sources: Cadence DE-HDL packaged netlist, KiCad conversion of 04192023_DAF0TMB3IC0_F0TG_MB_C_brd_V02_OCP.brd

C6672  Q_CAP_DIFFBUS  DIFF BUS_0.22UF 6.3V 20% X6S  pkg C0201  page 330 : \1\ = P5E_CPU1_P1_TX_BUF_C_DN<5> ; \2\ = P5E_CPU1_P1_TX_BUF_DN<5>
R6800  Q_RES  0 5% CHIP  pkg 0402LF  page 364 : A = GND ; B = P0V9_RETIMER_CPU1_EN1_R
C3921  Q_CAP  22UF 4V 20% X6S  pkg C0402  page 74 : A = PVDD11_S3_P1 ; B = GND

(kicad_pcb
	(version 20260206)
	(generator "pcbnew")
	(generator_version "10.0")
	(general
		(thickness 1.6)
		(legacy_teardrops no)
	)
	(paper "A4")
	(title_block
		(title "04192023_DAF0TMB3IC0_F0TG_MB_C_brd_V02_OCP.brd")
		(comment 1 "Grand Teton / footprints 6601-6603 of 8354")
	)
	(layers
		(0 "F.Cu" signal "TOP")
		(4 "In1.Cu" signal "GND")
		(6 "In2.Cu" signal "IN1")
		(8 "In3.Cu" signal "GND1")
		(10 "In4.Cu" signal "IN2")
		(12 "In5.Cu" signal "GND2")
		(14 "In6.Cu" signal "IN3")
		(16 "In7.Cu" signal "GND3")
		(18 "In8.Cu" signal "VCC")
		(20 "In9.Cu" signal "VCC1")
		(22 "In10.Cu" signal "GND4")
		(24 "In11.Cu" signal "IN4")
		(26 "In12.Cu" signal "GND5")
		(28 "In13.Cu" signal "IN5")
		(30 "In14.Cu" signal "GND6")
		(32 "In15.Cu" signal "IN6")
		(34 "In16.Cu" signal "GND7")
		(2 "B.Cu" signal "BOTTOM")
		(9 "F.Adhes" user "F.Adhesive")
		(11 "B.Adhes" user "B.Adhesive")
		(13 "F.Paste" user "Package Geometry/Pastemask Top")
		(15 "B.Paste" user "Package Geometry/Pastemask Bottom")
		(5 "F.SilkS" user "Ref Des/Silkscreen Top")
		(7 "B.SilkS" user "Ref Des/Silkscreen Bottom")
		(1 "F.Mask" user "Board Geometry/Soldermask Top")
		(3 "B.Mask" user "Board Geometry/Soldermask Bottom")
		(17 "Dwgs.User" user "User.Drawings")
		(19 "Cmts.User" user "User.Comments")
		(21 "Eco1.User" user "User.Eco1")
		(23 "Eco2.User" user "User.Eco2")
		(25 "Edge.Cuts" user "Board Geometry/Outline")
		(27 "Margin" user)
		(31 "F.CrtYd" user "Package Geometry/Place Bound Top")
		(29 "B.CrtYd" user "Package Geometry/Place Bound Bottom")
		(35 "F.Fab" user "Ref Des/Assembly Top")
		(33 "B.Fab" user "Ref Des/Assembly Bottom")
	)
	(footprint ""
		(layer "B.Cu")
		(at 107.677204 -261.748016 90)
		(property "Reference" "C3921"
			(at 0 0 90)
			(layer "B.SilkS")
			(hide yes)
			(effects
				(font
					(size 1.27 1.27)
				)
				(justify mirror)
			)
		)
		(property "Value" ""
			(at 0 0 90)
			(layer "B.Fab")
			(effects
				(font
					(size 1.27 1.27)
				)
				(justify mirror)
			)
		)
		(duplicate_pad_numbers_are_jumpers no)
		(fp_line
			(start 0.7874 -0.4064)
			(end -0.7874 -0.4064)
			(stroke
				(width 0.1524)
				(type default)
			)
			(layer "B.SilkS")
		)
		(fp_line
			(start -0.7874 -0.4064)
			(end -0.7874 0.4064)
			(stroke
				(width 0.1524)
				(type default)
			)
			(layer "B.SilkS")
		)
		(fp_line
			(start 0.7874 0.4064)
			(end 0.7874 -0.4064)
			(stroke
				(width 0.1524)
				(type default)
			)
			(layer "B.SilkS")
		)
		(fp_line
			(start -0.7874 0.4064)
			(end 0.7874 0.4064)
			(stroke
				(width 0.1524)
				(type default)
			)
			(layer "B.SilkS")
		)
		(fp_line
			(start 0.67945 -0.305054)
			(end 0.12065 -0.305054)
			(stroke
				(width 0.1)
				(type default)
			)
			(layer "B.Fab")
		)
		(fp_line
			(start 0.12065 -0.305054)
			(end 0.12065 -0.2794)
			(stroke
				(width 0.1)
				(type default)
			)
			(layer "B.Fab")
		)
		(fp_line
			(start -0.12065 -0.3048)
			(end -0.67945 -0.3048)
			(stroke
				(width 0.1)
				(type default)
			)
			(layer "B.Fab")
		)
		(fp_line
			(start -0.67945 -0.3048)
			(end -0.67945 0.3048)
			(stroke
				(width 0.1)
				(type default)
			)
			(layer "B.Fab")
		)
		(fp_line
			(start 0.12065 -0.2794)
			(end -0.12065 -0.2794)
			(stroke
				(width 0.1)
				(type default)
			)
			(layer "B.Fab")
		)
		(fp_line
			(start -0.12065 -0.2794)
			(end -0.12065 -0.3048)
			(stroke
				(width 0.1)
				(type default)
			)
			(layer "B.Fab")
		)
		(fp_line
			(start 0.12065 0.2794)
			(end 0.12065 0.3048)
			(stroke
				(width 0.1)
				(type default)
			)
			(layer "B.Fab")
		)
		(fp_line
			(start -0.120396 0.2794)
			(end 0.12065 0.2794)
			(stroke
				(width 0.1)
				(type default)
			)
			(layer "B.Fab")
		)
		(fp_line
			(start 0.67945 0.3048)
			(end 0.67945 -0.305054)
			(stroke
				(width 0.1)
				(type default)
			)
			(layer "B.Fab")
		)
		(fp_line
			(start 0.12065 0.3048)
			(end 0.67945 0.3048)
			(stroke
				(width 0.1)
				(type default)
			)
			(layer "B.Fab")
		)
		(fp_line
			(start -0.120396 0.3048)
			(end -0.120396 0.2794)
			(stroke
				(width 0.1)
				(type default)
			)
			(layer "B.Fab")
		)
		(fp_line
			(start -0.67945 0.3048)
			(end -0.120396 0.3048)
			(stroke
				(width 0.1)
				(type default)
			)
			(layer "B.Fab")
		)
		(pad "1" smd circle
			(at 0.40005 0 270)
			(size 0 0)
			(layers "B.Cu" "B.Mask" "B.Paste")
			(net "PVDD11_S3_P1")
		)
		(pad "2" smd circle
			(at -0.40005 0 270)
			(size 0 0)
			(layers "B.Cu" "B.Mask" "B.Paste")
			(net "GND")
		)
	)
	(footprint ""
		(layer "B.Cu")
		(at 64.616584 -408.517344 90)
		(property "Reference" "C6672"
			(at 0 0 90)
			(layer "B.SilkS")
			(hide yes)
			(effects
				(font
					(size 1.27 1.27)
				)
				(justify mirror)
			)
		)
		(property "Value" ""
			(at 0 0 90)
			(layer "B.Fab")
			(effects
				(font
					(size 1.27 1.27)
				)
				(justify mirror)
			)
		)
		(duplicate_pad_numbers_are_jumpers no)
		(fp_line
			(start 0.299974 -0.150114)
			(end -0.299974 -0.150114)
			(stroke
				(width 0.1)
				(type default)
			)
			(layer "B.Fab")
		)
		(fp_line
			(start -0.299974 -0.150114)
			(end -0.299974 0.150114)
			(stroke
				(width 0.1)
				(type default)
			)
			(layer "B.Fab")
		)
		(fp_line
			(start 0.299974 0.150114)
			(end 0.299974 -0.150114)
			(stroke
				(width 0.1)
				(type default)
			)
			(layer "B.Fab")
		)
		(fp_line
			(start -0.299974 0.150114)
			(end 0.299974 0.150114)
			(stroke
				(width 0.1)
				(type default)
			)
			(layer "B.Fab")
		)
		(pad "1" smd rect
			(at 0.2667 0 270)
			(size 0.3048 0.381)
			(layers "B.Cu" "B.Mask" "B.Paste")
			(net "P5E_CPU1_P1_TX_BUF_C_DN<5>")
		)
		(pad "2" smd rect
			(at -0.2667 0 270)
			(size 0.3048 0.381)
			(layers "B.Cu" "B.Mask" "B.Paste")
			(net "P5E_CPU1_P1_TX_BUF_DN<5>")
		)
	)
	(footprint ""
		(layer "B.Cu")
		(at 20.489418 -413.99587)
		(property "Reference" "R6800"
			(at 0 0 0)
			(layer "B.SilkS")
			(hide yes)
			(effects
				(font
					(size 1.27 1.27)
				)
				(justify mirror)
			)
		)
		(property "Value" ""
			(at 0 0 0)
			(layer "B.Fab")
			(effects
				(font
					(size 1.27 1.27)
				)
				(justify mirror)
			)
		)
		(duplicate_pad_numbers_are_jumpers no)
		(fp_line
			(start -0.7874 -0.4064)
			(end -0.7874 0.4064)
			(stroke
				(width 0.1524)
				(type default)
			)
			(layer "B.SilkS")
		)
		(fp_line
			(start -0.7874 0.4064)
			(end 0.7874 0.4064)
			(stroke
				(width 0.1524)
				(type default)
			)
			(layer "B.SilkS")
		)
		(fp_line
			(start 0.7874 -0.4064)
			(end -0.7874 -0.4064)
			(stroke
				(width 0.1524)
				(type default)
			)
			(layer "B.SilkS")
		)
		(fp_line
			(start 0.7874 0.4064)
			(end 0.7874 -0.4064)
			(stroke
				(width 0.1524)
				(type default)
			)
			(layer "B.SilkS")
		)
		(fp_line
			(start -0.67945 -0.3048)
			(end -0.67945 0.3048)
			(stroke
				(width 0.1)
				(type default)
			)
			(layer "B.Fab")
		)
		(fp_line
			(start -0.67945 0.3048)
			(end -0.120396 0.3048)
			(stroke
				(width 0.1)
				(type default)
			)
			(layer "B.Fab")
		)
		(fp_line
			(start -0.12065 -0.3048)
			(end -0.67945 -0.3048)
			(stroke
				(width 0.1)
				(type default)
			)
			(layer "B.Fab")
		)
		(fp_line
			(start -0.12065 -0.2794)
			(end -0.12065 -0.3048)
			(stroke
				(width 0.1)
				(type default)
			)
			(layer "B.Fab")
		)
		(fp_line
			(start -0.120396 0.2794)
			(end 0.12065 0.2794)
			(stroke
				(width 0.1)
				(type default)
			)
			(layer "B.Fab")
		)
		(fp_line
			(start -0.120396 0.3048)
			(end -0.120396 0.2794)
			(stroke
				(width 0.1)
				(type default)
			)
			(layer "B.Fab")
		)
		(fp_line
			(start 0.12065 -0.305054)
			(end 0.12065 -0.2794)
			(stroke
				(width 0.1)
				(type default)
			)
			(layer "B.Fab")
		)
		(fp_line
			(start 0.12065 -0.2794)
			(end -0.12065 -0.2794)
			(stroke
				(width 0.1)
				(type default)
			)
			(layer "B.Fab")
		)
		(fp_line
			(start 0.12065 0.2794)
			(end 0.12065 0.3048)
			(stroke
				(width 0.1)
				(type default)
			)
			(layer "B.Fab")
		)
		(fp_line
			(start 0.12065 0.3048)
			(end 0.67945 0.3048)
			(stroke
				(width 0.1)
				(type default)
			)
			(layer "B.Fab")
		)
		(fp_line
			(start 0.67945 -0.305054)
			(end 0.12065 -0.305054)
			(stroke
				(width 0.1)
				(type default)
			)
			(layer "B.Fab")
		)
		(fp_line
			(start 0.67945 0.3048)
			(end 0.67945 -0.305054)
			(stroke
				(width 0.1)
				(type default)
			)
			(layer "B.Fab")
		)
		(pad "1" smd circle
			(at 0.40005 0 180)
			(size 0 0)
			(layers "B.Cu" "B.Mask" "B.Paste")
			(net "GND")
		)
		(pad "2" smd circle
			(at -0.40005 0 180)
			(size 0 0)
			(layers "B.Cu" "B.Mask" "B.Paste")
			(net "P0V9_RETIMER_CPU1_EN1_R")
		)
	)
)
